(kicad_pcb
	(version 20260206)
	(generator "pcbnew")
	(generator_version "10.0")
	(general
		(thickness 1.6)
		(legacy_teardrops no)
	)
	(paper "A4")
	(title_block
		(title "03242023_DA0F0TMBIJ0_F0T_Motherboard_J_brd_V01_OCP.brd")
		(comment 1 "Grand Teton / footprints 2127-2133 of 6105")
	)
	(layers
		(0 "F.Cu" signal "TOP")
		(4 "In1.Cu" signal "GND")
		(6 "In2.Cu" signal "IN1")
		(8 "In3.Cu" signal "GND1")
		(10 "In4.Cu" signal "IN2")
		(12 "In5.Cu" signal "GND2")
		(14 "In6.Cu" signal "IN3")
		(16 "In7.Cu" signal "GND3")
		(18 "In8.Cu" signal "VCC")
		(20 "In9.Cu" signal "VCC1")
		(22 "In10.Cu" signal "GND4")
		(24 "In11.Cu" signal "IN4")
		(26 "In12.Cu" signal "GND5")
		(28 "In13.Cu" signal "IN5")
		(30 "In14.Cu" signal "GND6")
		(32 "In15.Cu" signal "IN6")
		(34 "In16.Cu" signal "GND7")
		(2 "B.Cu" signal "BOTTOM")
		(9 "F.Adhes" user "F.Adhesive")
		(11 "B.Adhes" user "B.Adhesive")
		(13 "F.Paste" user "Package Geometry/Pastemask Top")
		(15 "B.Paste" user "Package Geometry/Pastemask Bottom")
		(5 "F.SilkS" user "Ref Des/Silkscreen Top")
		(7 "B.SilkS" user "Ref Des/Silkscreen Bottom")
		(1 "F.Mask" user "Board Geometry/Soldermask Top")
		(3 "B.Mask" user "Board Geometry/Soldermask Bottom")
		(17 "Dwgs.User" user "User.Drawings")
		(19 "Cmts.User" user "User.Comments")
		(21 "Eco1.User" user "User.Eco1")
		(23 "Eco2.User" user "User.Eco2")
		(25 "Edge.Cuts" user "Board Geometry/Outline")
		(27 "Margin" user)
		(31 "F.CrtYd" user "Package Geometry/Place Bound Top")
		(29 "B.CrtYd" user "Package Geometry/Place Bound Bottom")
		(35 "F.Fab" user "Ref Des/Assembly Top")
		(33 "B.Fab" user "Ref Des/Assembly Bottom")
	)
	(footprint ""
		(layer "F.Cu")
		(at 122.238516 -338.17814 90)
		(property "Reference" "PR1788"
			(at 0 0 90)
			(layer "F.SilkS")
			(hide yes)
			(effects
				(font
					(size 1.27 1.27)
				)
			)
		)
		(property "Value" ""
			(at 0 0 90)
			(layer "F.Fab")
			(effects
				(font
					(size 1.27 1.27)
				)
			)
		)
		(duplicate_pad_numbers_are_jumpers no)
		(fp_line
			(start 0.7874 -0.4064)
			(end 0.7874 0.4064)
			(stroke
				(width 0.1524)
				(type default)
			)
			(layer "F.SilkS")
		)
		(fp_line
			(start -0.7874 -0.4064)
			(end 0.7874 -0.4064)
			(stroke
				(width 0.1524)
				(type default)
			)
			(layer "F.SilkS")
		)
		(fp_line
			(start 0.7874 0.4064)
			(end -0.7874 0.4064)
			(stroke
				(width 0.1524)
				(type default)
			)
			(layer "F.SilkS")
		)
		(fp_line
			(start -0.7874 0.4064)
			(end -0.7874 -0.4064)
			(stroke
				(width 0.1524)
				(type default)
			)
			(layer "F.SilkS")
		)
		(fp_line
			(start -0.12065 -0.305054)
			(end -0.12065 -0.2794)
			(stroke
				(width 0.1)
				(type default)
			)
			(layer "F.Fab")
		)
		(fp_line
			(start -0.67945 -0.305054)
			(end -0.12065 -0.305054)
			(stroke
				(width 0.1)
				(type default)
			)
			(layer "F.Fab")
		)
		(fp_line
			(start 0.67945 -0.3048)
			(end 0.67945 0.3048)
			(stroke
				(width 0.1)
				(type default)
			)
			(layer "F.Fab")
		)
		(fp_line
			(start 0.12065 -0.3048)
			(end 0.67945 -0.3048)
			(stroke
				(width 0.1)
				(type default)
			)
			(layer "F.Fab")
		)
		(fp_line
			(start 0.12065 -0.2794)
			(end 0.12065 -0.3048)
			(stroke
				(width 0.1)
				(type default)
			)
			(layer "F.Fab")
		)
		(fp_line
			(start -0.12065 -0.2794)
			(end 0.12065 -0.2794)
			(stroke
				(width 0.1)
				(type default)
			)
			(layer "F.Fab")
		)
		(fp_line
			(start 0.120396 0.2794)
			(end -0.12065 0.2794)
			(stroke
				(width 0.1)
				(type default)
			)
			(layer "F.Fab")
		)
		(fp_line
			(start -0.12065 0.2794)
			(end -0.12065 0.3048)
			(stroke
				(width 0.1)
				(type default)
			)
			(layer "F.Fab")
		)
		(fp_line
			(start 0.67945 0.3048)
			(end 0.120396 0.3048)
			(stroke
				(width 0.1)
				(type default)
			)
			(layer "F.Fab")
		)
		(fp_line
			(start 0.120396 0.3048)
			(end 0.120396 0.2794)
			(stroke
				(width 0.1)
				(type default)
			)
			(layer "F.Fab")
		)
		(fp_line
			(start -0.12065 0.3048)
			(end -0.67945 0.3048)
			(stroke
				(width 0.1)
				(type default)
			)
			(layer "F.Fab")
		)
		(fp_line
			(start -0.67945 0.3048)
			(end -0.67945 -0.305054)
			(stroke
				(width 0.1)
				(type default)
			)
			(layer "F.Fab")
		)
		(pad "1" smd circle
			(at -0.40005 0 90)
			(size 0 0)
			(layers "F.Cu" "F.Mask" "F.Paste")
			(net "SW_PVCCIN_CPU1_BOOT4")
		)
		(pad "2" smd circle
			(at 0.40005 0 90)
			(size 0 0)
			(layers "F.Cu" "F.Mask" "F.Paste")
			(net "SW_PVCCIN_CPU1_BOOT4_R")
		)
	)
	(footprint ""
		(layer "F.Cu")
		(at 200.057004 -77.06614 180)
		(property "Reference" "R1292"
			(at 0 0 180)
			(layer "F.SilkS")
			(hide yes)
			(effects
				(font
					(size 1.27 1.27)
				)
			)
		)
		(property "Value" ""
			(at 0 0 180)
			(layer "F.Fab")
			(effects
				(font
					(size 1.27 1.27)
				)
			)
		)
		(duplicate_pad_numbers_are_jumpers no)
		(fp_line
			(start 0.7874 0.4064)
			(end -0.7874 0.4064)
			(stroke
				(width 0.1524)
				(type default)
			)
			(layer "F.SilkS")
		)
		(fp_line
			(start 0.7874 -0.4064)
			(end 0.7874 0.4064)
			(stroke
				(width 0.1524)
				(type default)
			)
			(layer "F.SilkS")
		)
		(fp_line
			(start -0.7874 0.4064)
			(end -0.7874 -0.4064)
			(stroke
				(width 0.1524)
				(type default)
			)
			(layer "F.SilkS")
		)
		(fp_line
			(start -0.7874 -0.4064)
			(end 0.7874 -0.4064)
			(stroke
				(width 0.1524)
				(type default)
			)
			(layer "F.SilkS")
		)
		(fp_line
			(start 0.67945 0.3048)
			(end 0.120396 0.3048)
			(stroke
				(width 0.1)
				(type default)
			)
			(layer "F.Fab")
		)
		(fp_line
			(start 0.67945 -0.3048)
			(end 0.67945 0.3048)
			(stroke
				(width 0.1)
				(type default)
			)
			(layer "F.Fab")
		)
		(fp_line
			(start 0.12065 -0.2794)
			(end 0.12065 -0.3048)
			(stroke
				(width 0.1)
				(type default)
			)
			(layer "F.Fab")
		)
		(fp_line
			(start 0.12065 -0.3048)
			(end 0.67945 -0.3048)
			(stroke
				(width 0.1)
				(type default)
			)
			(layer "F.Fab")
		)
		(fp_line
			(start 0.120396 0.3048)
			(end 0.120396 0.2794)
			(stroke
				(width 0.1)
				(type default)
			)
			(layer "F.Fab")
		)
		(fp_line
			(start 0.120396 0.2794)
			(end -0.12065 0.2794)
			(stroke
				(width 0.1)
				(type default)
			)
			(layer "F.Fab")
		)
		(fp_line
			(start -0.12065 0.3048)
			(end -0.67945 0.3048)
			(stroke
				(width 0.1)
				(type default)
			)
			(layer "F.Fab")
		)
		(fp_line
			(start -0.12065 0.2794)
			(end -0.12065 0.3048)
			(stroke
				(width 0.1)
				(type default)
			)
			(layer "F.Fab")
		)
		(fp_line
			(start -0.12065 -0.2794)
			(end 0.12065 -0.2794)
			(stroke
				(width 0.1)
				(type default)
			)
			(layer "F.Fab")
		)
		(fp_line
			(start -0.12065 -0.305054)
			(end -0.12065 -0.2794)
			(stroke
				(width 0.1)
				(type default)
			)
			(layer "F.Fab")
		)
		(fp_line
			(start -0.67945 0.3048)
			(end -0.67945 -0.305054)
			(stroke
				(width 0.1)
				(type default)
			)
			(layer "F.Fab")
		)
		(fp_line
			(start -0.67945 -0.305054)
			(end -0.12065 -0.305054)
			(stroke
				(width 0.1)
				(type default)
			)
			(layer "F.Fab")
		)
		(pad "1" smd circle
			(at -0.40005 0 180)
			(size 0 0)
			(layers "F.Cu" "F.Mask" "F.Paste")
			(net "NCSI_BMC_RXD0_R")
		)
		(pad "2" smd circle
			(at 0.40005 0 180)
			(size 0 0)
			(layers "F.Cu" "F.Mask" "F.Paste")
			(net "RMII_OCP_BMC_RXD_0")
		)
	)
	(footprint ""
		(layer "F.Cu")
		(at 306.263294 -15.50924 180)
		(property "Reference" "R2489"
			(at 0 0 180)
			(layer "F.SilkS")
			(hide yes)
			(effects
				(font
					(size 1.27 1.27)
				)
			)
		)
		(property "Value" ""
			(at 0 0 180)
			(layer "F.Fab")
			(effects
				(font
					(size 1.27 1.27)
				)
			)
		)
		(duplicate_pad_numbers_are_jumpers no)
		(fp_line
			(start 0.7874 0.4064)
			(end -0.7874 0.4064)
			(stroke
				(width 0.1524)
				(type default)
			)
			(layer "F.SilkS")
		)
		(fp_line
			(start 0.7874 -0.4064)
			(end 0.7874 0.4064)
			(stroke
				(width 0.1524)
				(type default)
			)
			(layer "F.SilkS")
		)
		(fp_line
			(start -0.7874 0.4064)
			(end -0.7874 -0.4064)
			(stroke
				(width 0.1524)
				(type default)
			)
			(layer "F.SilkS")
		)
		(fp_line
			(start -0.7874 -0.4064)
			(end 0.7874 -0.4064)
			(stroke
				(width 0.1524)
				(type default)
			)
			(layer "F.SilkS")
		)
		(fp_line
			(start 0.67945 0.3048)
			(end 0.120396 0.3048)
			(stroke
				(width 0.1)
				(type default)
			)
			(layer "F.Fab")
		)
		(fp_line
			(start 0.67945 -0.3048)
			(end 0.67945 0.3048)
			(stroke
				(width 0.1)
				(type default)
			)
			(layer "F.Fab")
		)
		(fp_line
			(start 0.12065 -0.2794)
			(end 0.12065 -0.3048)
			(stroke
				(width 0.1)
				(type default)
			)
			(layer "F.Fab")
		)
		(fp_line
			(start 0.12065 -0.3048)
			(end 0.67945 -0.3048)
			(stroke
				(width 0.1)
				(type default)
			)
			(layer "F.Fab")
		)
		(fp_line
			(start 0.120396 0.3048)
			(end 0.120396 0.2794)
			(stroke
				(width 0.1)
				(type default)
			)
			(layer "F.Fab")
		)
		(fp_line
			(start 0.120396 0.2794)
			(end -0.12065 0.2794)
			(stroke
				(width 0.1)
				(type default)
			)
			(layer "F.Fab")
		)
		(fp_line
			(start -0.12065 0.3048)
			(end -0.67945 0.3048)
			(stroke
				(width 0.1)
				(type default)
			)
			(layer "F.Fab")
		)
		(fp_line
			(start -0.12065 0.2794)
			(end -0.12065 0.3048)
			(stroke
				(width 0.1)
				(type default)
			)
			(layer "F.Fab")
		)
		(fp_line
			(start -0.12065 -0.2794)
			(end 0.12065 -0.2794)
			(stroke
				(width 0.1)
				(type default)
			)
			(layer "F.Fab")
		)
		(fp_line
			(start -0.12065 -0.305054)
			(end -0.12065 -0.2794)
			(stroke
				(width 0.1)
				(type default)
			)
			(layer "F.Fab")
		)
		(fp_line
			(start -0.67945 0.3048)
			(end -0.67945 -0.305054)
			(stroke
				(width 0.1)
				(type default)
			)
			(layer "F.Fab")
		)
		(fp_line
			(start -0.67945 -0.305054)
			(end -0.12065 -0.305054)
			(stroke
				(width 0.1)
				(type default)
			)
			(layer "F.Fab")
		)
		(pad "1" smd circle
			(at -0.40005 0 180)
			(size 0 0)
			(layers "F.Cu" "F.Mask" "F.Paste")
			(net "IRQ_LVC3_WAKE_BUF_N")
		)
		(pad "2" smd circle
			(at 0.40005 0 180)
			(size 0 0)
			(layers "F.Cu" "F.Mask" "F.Paste")
			(net "IRQ_LVC3_WAKE_N")
		)
	)
	(footprint ""
		(layer "F.Cu")
		(at 368.243358 -92.962984 90)
		(property "Reference" "R3055"
			(at 0 0 90)
			(layer "F.SilkS")
			(hide yes)
			(effects
				(font
					(size 1.27 1.27)
				)
			)
		)
		(property "Value" ""
			(at 0 0 90)
			(layer "F.Fab")
			(effects
				(font
					(size 1.27 1.27)
				)
			)
		)
		(duplicate_pad_numbers_are_jumpers no)
		(fp_line
			(start 0.7874 -0.4064)
			(end 0.7874 0.4064)
			(stroke
				(width 0.1524)
				(type default)
			)
			(layer "F.SilkS")
		)
		(fp_line
			(start -0.7874 -0.4064)
			(end 0.7874 -0.4064)
			(stroke
				(width 0.1524)
				(type default)
			)
			(layer "F.SilkS")
		)
		(fp_line
			(start 0.7874 0.4064)
			(end -0.7874 0.4064)
			(stroke
				(width 0.1524)
				(type default)
			)
			(layer "F.SilkS")
		)
		(fp_line
			(start -0.7874 0.4064)
			(end -0.7874 -0.4064)
			(stroke
				(width 0.1524)
				(type default)
			)
			(layer "F.SilkS")
		)
		(fp_line
			(start -0.12065 -0.305054)
			(end -0.12065 -0.2794)
			(stroke
				(width 0.1)
				(type default)
			)
			(layer "F.Fab")
		)
		(fp_line
			(start -0.67945 -0.305054)
			(end -0.12065 -0.305054)
			(stroke
				(width 0.1)
				(type default)
			)
			(layer "F.Fab")
		)
		(fp_line
			(start 0.67945 -0.3048)
			(end 0.67945 0.3048)
			(stroke
				(width 0.1)
				(type default)
			)
			(layer "F.Fab")
		)
		(fp_line
			(start 0.12065 -0.3048)
			(end 0.67945 -0.3048)
			(stroke
				(width 0.1)
				(type default)
			)
			(layer "F.Fab")
		)
		(fp_line
			(start 0.12065 -0.2794)
			(end 0.12065 -0.3048)
			(stroke
				(width 0.1)
				(type default)
			)
			(layer "F.Fab")
		)
		(fp_line
			(start -0.12065 -0.2794)
			(end 0.12065 -0.2794)
			(stroke
				(width 0.1)
				(type default)
			)
			(layer "F.Fab")
		)
		(fp_line
			(start 0.120396 0.2794)
			(end -0.12065 0.2794)
			(stroke
				(width 0.1)
				(type default)
			)
			(layer "F.Fab")
		)
		(fp_line
			(start -0.12065 0.2794)
			(end -0.12065 0.3048)
			(stroke
				(width 0.1)
				(type default)
			)
			(layer "F.Fab")
		)
		(fp_line
			(start 0.67945 0.3048)
			(end 0.120396 0.3048)
			(stroke
				(width 0.1)
				(type default)
			)
			(layer "F.Fab")
		)
		(fp_line
			(start 0.120396 0.3048)
			(end 0.120396 0.2794)
			(stroke
				(width 0.1)
				(type default)
			)
			(layer "F.Fab")
		)
		(fp_line
			(start -0.12065 0.3048)
			(end -0.67945 0.3048)
			(stroke
				(width 0.1)
				(type default)
			)
			(layer "F.Fab")
		)
		(fp_line
			(start -0.67945 0.3048)
			(end -0.67945 -0.305054)
			(stroke
				(width 0.1)
				(type default)
			)
			(layer "F.Fab")
		)
		(pad "1" smd circle
			(at -0.40005 0 90)
			(size 0 0)
			(layers "F.Cu" "F.Mask" "F.Paste")
			(net "P3V3_AUX")
		)
		(pad "2" smd circle
			(at 0.40005 0 90)
			(size 0 0)
			(layers "F.Cu" "F.Mask" "F.Paste")
			(net "PU_GTL2014_BMC_JTAG_DIR_1")
		)
	)
	(footprint ""
		(layer "F.Cu")
		(at 57.144158 -402.371052 -90)
		(property "Reference" "C716"
			(at 0 0 270)
			(layer "F.SilkS")
			(hide yes)
			(effects
				(font
					(size 1.27 1.27)
				)
			)
		)
		(property "Value" ""
			(at 0 0 270)
			(layer "F.Fab")
			(effects
				(font
					(size 1.27 1.27)
				)
			)
		)
		(duplicate_pad_numbers_are_jumpers no)
		(fp_line
			(start -0.299974 0.150114)
			(end -0.299974 -0.150114)
			(stroke
				(width 0.1)
				(type default)
			)
			(layer "F.Fab")
		)
		(fp_line
			(start 0.299974 0.150114)
			(end -0.299974 0.150114)
			(stroke
				(width 0.1)
				(type default)
			)
			(layer "F.Fab")
		)
		(fp_line
			(start -0.299974 -0.150114)
			(end 0.299974 -0.150114)
			(stroke
				(width 0.1)
				(type default)
			)
			(layer "F.Fab")
		)
		(fp_line
			(start 0.299974 -0.150114)
			(end 0.299974 0.150114)
			(stroke
				(width 0.1)
				(type default)
			)
			(layer "F.Fab")
		)
		(pad "1" smd rect
			(at -0.2667 0 270)
			(size 0.3048 0.381)
			(layers "F.Cu" "F.Mask" "F.Paste")
			(net "P5E_CPU1_PE0_TX_C_DN<12>")
		)
		(pad "2" smd rect
			(at 0.2667 0 270)
			(size 0.3048 0.381)
			(layers "F.Cu" "F.Mask" "F.Paste")
			(net "P5E_CPU1_PE0_TX_DN<12>")
		)
	)
	(footprint ""
		(layer "F.Cu")
		(at 320.617088 -408.517344 -90)
		(property "Reference" "C912"
			(at 0 0 270)
			(layer "F.SilkS")
			(hide yes)
			(effects
				(font
					(size 1.27 1.27)
				)
			)
		)
		(property "Value" ""
			(at 0 0 270)
			(layer "F.Fab")
			(effects
				(font
					(size 1.27 1.27)
				)
			)
		)
		(duplicate_pad_numbers_are_jumpers no)
		(fp_line
			(start -0.299974 0.150114)
			(end -0.299974 -0.150114)
			(stroke
				(width 0.1)
				(type default)
			)
			(layer "F.Fab")
		)
		(fp_line
			(start 0.299974 0.150114)
			(end -0.299974 0.150114)
			(stroke
				(width 0.1)
				(type default)
			)
			(layer "F.Fab")
		)
		(fp_line
			(start -0.299974 -0.150114)
			(end 0.299974 -0.150114)
			(stroke
				(width 0.1)
				(type default)
			)
			(layer "F.Fab")
		)
		(fp_line
			(start 0.299974 -0.150114)
			(end 0.299974 0.150114)
			(stroke
				(width 0.1)
				(type default)
			)
			(layer "F.Fab")
		)
		(pad "1" smd rect
			(at -0.2667 0 270)
			(size 0.3048 0.381)
			(layers "F.Cu" "F.Mask" "F.Paste")
			(net "P5E_CPU0_PE0_TX_C_DN<10>")
		)
		(pad "2" smd rect
			(at 0.2667 0 270)
			(size 0.3048 0.381)
			(layers "F.Cu" "F.Mask" "F.Paste")
			(net "P5E_CPU0_PE0_TX_DN<10>")
		)
	)
	(footprint ""
		(layer "F.Cu")
		(at 392.119866 -31.185612 -90)
		(property "Reference" "R1593"
			(at 0 0 270)
			(layer "F.SilkS")
			(hide yes)
			(effects
				(font
					(size 1.27 1.27)
				)
			)
		)
		(property "Value" ""
			(at 0 0 270)
			(layer "F.Fab")
			(effects
				(font
					(size 1.27 1.27)
				)
			)
		)
		(duplicate_pad_numbers_are_jumpers no)
		(fp_line
			(start -0.7874 0.4064)
			(end -0.7874 -0.4064)
			(stroke
				(width 0.1524)
				(type default)
			)
			(layer "F.SilkS")
		)
		(fp_line
			(start 0.7874 0.4064)
			(end -0.7874 0.4064)
			(stroke
				(width 0.1524)
				(type default)
			)
			(layer "F.SilkS")
		)
		(fp_line
			(start -0.7874 -0.4064)
			(end 0.7874 -0.4064)
			(stroke
				(width 0.1524)
				(type default)
			)
			(layer "F.SilkS")
		)
		(fp_line
			(start 0.7874 -0.4064)
			(end 0.7874 0.4064)
			(stroke
				(width 0.1524)
				(type default)
			)
			(layer "F.SilkS")
		)
		(fp_line
			(start -0.67945 0.3048)
			(end -0.67945 -0.305054)
			(stroke
				(width 0.1)
				(type default)
			)
			(layer "F.Fab")
		)
		(fp_line
			(start -0.12065 0.3048)
			(end -0.67945 0.3048)
			(stroke
				(width 0.1)
				(type default)
			)
			(layer "F.Fab")
		)
		(fp_line
			(start 0.120396 0.3048)
			(end 0.120396 0.2794)
			(stroke
				(width 0.1)
				(type default)
			)
			(layer "F.Fab")
		)
		(fp_line
			(start 0.67945 0.3048)
			(end 0.120396 0.3048)
			(stroke
				(width 0.1)
				(type default)
			)
			(layer "F.Fab")
		)
		(fp_line
			(start -0.12065 0.2794)
			(end -0.12065 0.3048)
			(stroke
				(width 0.1)
				(type default)
			)
			(layer "F.Fab")
		)
		(fp_line
			(start 0.120396 0.2794)
			(end -0.12065 0.2794)
			(stroke
				(width 0.1)
				(type default)
			)
			(layer "F.Fab")
		)
		(fp_line
			(start -0.12065 -0.2794)
			(end 0.12065 -0.2794)
			(stroke
				(width 0.1)
				(type default)
			)
			(layer "F.Fab")
		)
		(fp_line
			(start 0.12065 -0.2794)
			(end 0.12065 -0.3048)
			(stroke
				(width 0.1)
				(type default)
			)
			(layer "F.Fab")
		)
		(fp_line
			(start 0.12065 -0.3048)
			(end 0.67945 -0.3048)
			(stroke
				(width 0.1)
				(type default)
			)
			(layer "F.Fab")
		)
		(fp_line
			(start 0.67945 -0.3048)
			(end 0.67945 0.3048)
			(stroke
				(width 0.1)
				(type default)
			)
			(layer "F.Fab")
		)
		(fp_line
			(start -0.67945 -0.305054)
			(end -0.12065 -0.305054)
			(stroke
				(width 0.1)
				(type default)
			)
			(layer "F.Fab")
		)
		(fp_line
			(start -0.12065 -0.305054)
			(end -0.12065 -0.2794)
			(stroke
				(width 0.1)
				(type default)
			)
			(layer "F.Fab")
		)
		(pad "1" smd circle
			(at -0.40005 0 270)
			(size 0 0)
			(layers "F.Cu" "F.Mask" "F.Paste")
			(net "P3V3_AUX")
		)
		(pad "2" smd circle
			(at 0.40005 0 270)
			(size 0 0)
			(layers "F.Cu" "F.Mask" "F.Paste")
			(net "OCP_SFF_PWRBRK_BUFF_N")
		)
	)
)
